# SCM (Grand Teton) — schematic netlist excerpt (pin names and nets, part order shuffled) for the footprints in the layout excerpt that follows; sources: Cadence DE-HDL packaged netlist, KiCad conversion of 12092022_DA0F0TMDCD0_F0T_Management_Board_D_brd_V3_OCP.brd

Q11  MOSFET_N_GSD  NX7002AK IC  pkg SOT23_GDSXE  page 15
  DRAIN  = P3V_BAT_R1
  GATE  = BATTERY_DETECT_R
  SOURCE  = P3V_BAT_SENSOR

R250  Q_RES  402 1% CHIP  pkg 0402LF  page 27 : A = P3V3_AUX ; B = SMB_BMC_MM4_SCL
R15  Q_RES  1K 1% CHIP  pkg 0402LF  page 26 : A = PD_FRU_WC_N ; B = GND

(kicad_pcb
	(version 20260206)
	(generator "pcbnew")
	(generator_version "10.0")
	(general
		(thickness 1.6)
		(legacy_teardrops no)
	)
	(paper "A4")
	(title_block
		(title "12092022_DA0F0TMDCD0_F0T_Management_Board_D_brd_V3_OCP.brd")
		(comment 1 "Grand Teton / footprints 1421-1423 of 1440")
	)
	(layers
		(0 "F.Cu" signal "TOP")
		(4 "In1.Cu" signal "GND")
		(6 "In2.Cu" signal "IN1")
		(8 "In3.Cu" signal "GND1")
		(10 "In4.Cu" signal "IN2")
		(12 "In5.Cu" signal "VCC")
		(14 "In6.Cu" signal "VCC1")
		(16 "In7.Cu" signal "IN3")
		(18 "In8.Cu" signal "GND2")
		(20 "In9.Cu" signal "IN4")
		(22 "In10.Cu" signal "GND3")
		(2 "B.Cu" signal "BOTTOM")
		(9 "F.Adhes" user "F.Adhesive")
		(11 "B.Adhes" user "B.Adhesive")
		(13 "F.Paste" user "Package Geometry/Pastemask Top")
		(15 "B.Paste" user "Package Geometry/Pastemask Bottom")
		(5 "F.SilkS" user "Ref Des/Silkscreen Top")
		(7 "B.SilkS" user "Ref Des/Silkscreen Bottom")
		(1 "F.Mask" user "Board Geometry/Soldermask Top")
		(3 "B.Mask" user "Board Geometry/Soldermask Bottom")
		(17 "Dwgs.User" user "User.Drawings")
		(19 "Cmts.User" user "User.Comments")
		(21 "Eco1.User" user "User.Eco1")
		(23 "Eco2.User" user "User.Eco2")
		(25 "Edge.Cuts" user "Board Geometry/Outline")
		(27 "Margin" user)
		(31 "F.CrtYd" user "Package Geometry/Place Bound Top")
		(29 "B.CrtYd" user "Package Geometry/Place Bound Bottom")
		(35 "F.Fab" user "Ref Des/Assembly Top")
		(33 "B.Fab" user "Ref Des/Assembly Bottom")
	)
	(footprint ""
		(layer "B.Cu")
		(at 68.58254 -29.810964)
		(property "Reference" "R15"
			(at 0 0 0)
			(layer "B.SilkS")
			(hide yes)
			(effects
				(font
					(size 1.27 1.27)
				)
				(justify mirror)
			)
		)
		(property "Value" ""
			(at 0 0 0)
			(layer "B.Fab")
			(effects
				(font
					(size 1.27 1.27)
				)
				(justify mirror)
			)
		)
		(duplicate_pad_numbers_are_jumpers no)
		(fp_line
			(start -0.7874 -0.4064)
			(end -0.7874 0.4064)
			(stroke
				(width 0.1524)
				(type default)
			)
			(layer "B.SilkS")
		)
		(fp_line
			(start -0.7874 0.4064)
			(end 0.7874 0.4064)
			(stroke
				(width 0.1524)
				(type default)
			)
			(layer "B.SilkS")
		)
		(fp_line
			(start 0.7874 -0.4064)
			(end -0.7874 -0.4064)
			(stroke
				(width 0.1524)
				(type default)
			)
			(layer "B.SilkS")
		)
		(fp_line
			(start 0.7874 0.4064)
			(end 0.7874 -0.4064)
			(stroke
				(width 0.1524)
				(type default)
			)
			(layer "B.SilkS")
		)
		(fp_line
			(start -0.67945 -0.3048)
			(end -0.67945 0.3048)
			(stroke
				(width 0.1)
				(type default)
			)
			(layer "B.Fab")
		)
		(fp_line
			(start -0.67945 0.3048)
			(end -0.120396 0.3048)
			(stroke
				(width 0.1)
				(type default)
			)
			(layer "B.Fab")
		)
		(fp_line
			(start -0.12065 -0.3048)
			(end -0.67945 -0.3048)
			(stroke
				(width 0.1)
				(type default)
			)
			(layer "B.Fab")
		)
		(fp_line
			(start -0.12065 -0.2794)
			(end -0.12065 -0.3048)
			(stroke
				(width 0.1)
				(type default)
			)
			(layer "B.Fab")
		)
		(fp_line
			(start -0.120396 0.2794)
			(end 0.12065 0.2794)
			(stroke
				(width 0.1)
				(type default)
			)
			(layer "B.Fab")
		)
		(fp_line
			(start -0.120396 0.3048)
			(end -0.120396 0.2794)
			(stroke
				(width 0.1)
				(type default)
			)
			(layer "B.Fab")
		)
		(fp_line
			(start 0.12065 -0.305054)
			(end 0.12065 -0.2794)
			(stroke
				(width 0.1)
				(type default)
			)
			(layer "B.Fab")
		)
		(fp_line
			(start 0.12065 -0.2794)
			(end -0.12065 -0.2794)
			(stroke
				(width 0.1)
				(type default)
			)
			(layer "B.Fab")
		)
		(fp_line
			(start 0.12065 0.2794)
			(end 0.12065 0.3048)
			(stroke
				(width 0.1)
				(type default)
			)
			(layer "B.Fab")
		)
		(fp_line
			(start 0.12065 0.3048)
			(end 0.67945 0.3048)
			(stroke
				(width 0.1)
				(type default)
			)
			(layer "B.Fab")
		)
		(fp_line
			(start 0.67945 -0.305054)
			(end 0.12065 -0.305054)
			(stroke
				(width 0.1)
				(type default)
			)
			(layer "B.Fab")
		)
		(fp_line
			(start 0.67945 0.3048)
			(end 0.67945 -0.305054)
			(stroke
				(width 0.1)
				(type default)
			)
			(layer "B.Fab")
		)
		(pad "1" smd circle
			(at 0.40005 0 180)
			(size 0 0)
			(layers "B.Cu" "B.Mask" "B.Paste")
			(net "PD_FRU_WC_N")
		)
		(pad "2" smd circle
			(at -0.40005 0 180)
			(size 0 0)
			(layers "B.Cu" "B.Mask" "B.Paste")
			(net "GND")
		)
	)
	(footprint ""
		(layer "B.Cu")
		(at 43.511216 -73.955148)
		(property "Reference" "Q11"
			(at -3.328416 -0.922782 0)
			(unlocked yes)
			(layer "B.SilkS")
			(effects
				(font
					(size 0.7874 0.5842)
					(thickness 0.1524)
				)
				(justify mirror)
			)
		)
		(property "Value" ""
			(at 0 0 0)
			(layer "B.Fab")
			(effects
				(font
					(size 1.27 1.27)
				)
				(justify mirror)
			)
		)
		(duplicate_pad_numbers_are_jumpers no)
		(fp_line
			(start -1.8796 -0.746252)
			(end -1.8796 0.803148)
			(stroke
				(width 0.1524)
				(type default)
			)
			(layer "B.SilkS")
		)
		(fp_line
			(start -1.423416 1.651)
			(end 1.8796 1.651)
			(stroke
				(width 0.1524)
				(type default)
			)
			(layer "B.SilkS")
		)
		(fp_line
			(start 1.8796 -1.651)
			(end -0.915416 -1.651)
			(stroke
				(width 0.1524)
				(type default)
			)
			(layer "B.SilkS")
		)
		(fp_line
			(start 1.8796 1.651)
			(end 1.8796 -1.651)
			(stroke
				(width 0.1524)
				(type default)
			)
			(layer "B.SilkS")
		)
		(fp_line
			(start -0.700024 -1.500124)
			(end -0.700024 1.500124)
			(stroke
				(width 0.1)
				(type default)
			)
			(layer "B.Fab")
		)
		(fp_line
			(start -0.700024 1.500124)
			(end 0.700024 1.500124)
			(stroke
				(width 0.1)
				(type default)
			)
			(layer "B.Fab")
		)
		(fp_line
			(start 0.700024 -1.500124)
			(end -0.700024 -1.500124)
			(stroke
				(width 0.1)
				(type default)
			)
			(layer "B.Fab")
		)
		(fp_line
			(start 0.700024 1.500124)
			(end 0.700024 -1.500124)
			(stroke
				(width 0.1)
				(type default)
			)
			(layer "B.Fab")
		)
		(pad "D" smd rect
			(at -1.119886 0 270)
			(size 1.016 1.2192)
			(layers "B.Cu" "B.Mask" "B.Paste")
			(net "P3V_BAT_R1")
		)
		(pad "G" smd rect
			(at 1.119886 -0.999998 270)
			(size 1.016 1.2192)
			(layers "B.Cu" "B.Mask" "B.Paste")
			(net "BATTERY_DETECT_R")
		)
		(pad "S" smd rect
			(at 1.119886 0.999998 270)
			(size 1.016 1.2192)
			(layers "B.Cu" "B.Mask" "B.Paste")
			(net "P3V_BAT_SENSOR")
		)
	)
	(footprint ""
		(layer "B.Cu")
		(at 45.405294 -30.816804 -90)
		(property "Reference" "R250"
			(at 0 0 90)
			(layer "B.SilkS")
			(hide yes)
			(effects
				(font
					(size 1.27 1.27)
				)
				(justify mirror)
			)
		)
		(property "Value" ""
			(at 0 0 90)
			(layer "B.Fab")
			(effects
				(font
					(size 1.27 1.27)
				)
				(justify mirror)
			)
		)
		(duplicate_pad_numbers_are_jumpers no)
		(fp_line
			(start -0.7874 0.4064)
			(end 0.7874 0.4064)
			(stroke
				(width 0.1524)
				(type default)
			)
			(layer "B.SilkS")
		)
		(fp_line
			(start 0.7874 0.4064)
			(end 0.7874 -0.4064)
			(stroke
				(width 0.1524)
				(type default)
			)
			(layer "B.SilkS")
		)
		(fp_line
			(start -0.7874 -0.4064)
			(end -0.7874 0.4064)
			(stroke
				(width 0.1524)
				(type default)
			)
			(layer "B.SilkS")
		)
		(fp_line
			(start 0.7874 -0.4064)
			(end -0.7874 -0.4064)
			(stroke
				(width 0.1524)
				(type default)
			)
			(layer "B.SilkS")
		)
		(fp_line
			(start -0.67945 0.3048)
			(end -0.120396 0.3048)
			(stroke
				(width 0.1)
				(type default)
			)
			(layer "B.Fab")
		)
		(fp_line
			(start -0.120396 0.3048)
			(end -0.120396 0.2794)
			(stroke
				(width 0.1)
				(type default)
			)
			(layer "B.Fab")
		)
		(fp_line
			(start 0.12065 0.3048)
			(end 0.67945 0.3048)
			(stroke
				(width 0.1)
				(type default)
			)
			(layer "B.Fab")
		)
		(fp_line
			(start 0.67945 0.3048)
			(end 0.67945 -0.305054)
			(stroke
				(width 0.1)
				(type default)
			)
			(layer "B.Fab")
		)
		(fp_line
			(start -0.120396 0.2794)
			(end 0.12065 0.2794)
			(stroke
				(width 0.1)
				(type default)
			)
			(layer "B.Fab")
		)
		(fp_line
			(start 0.12065 0.2794)
			(end 0.12065 0.3048)
			(stroke
				(width 0.1)
				(type default)
			)
			(layer "B.Fab")
		)
		(fp_line
			(start -0.12065 -0.2794)
			(end -0.12065 -0.3048)
			(stroke
				(width 0.1)
				(type default)
			)
			(layer "B.Fab")
		)
		(fp_line
			(start 0.12065 -0.2794)
			(end -0.12065 -0.2794)
			(stroke
				(width 0.1)
				(type default)
			)
			(layer "B.Fab")
		)
		(fp_line
			(start -0.67945 -0.3048)
			(end -0.67945 0.3048)
			(stroke
				(width 0.1)
				(type default)
			)
			(layer "B.Fab")
		)
		(fp_line
			(start -0.12065 -0.3048)
			(end -0.67945 -0.3048)
			(stroke
				(width 0.1)
				(type default)
			)
			(layer "B.Fab")
		)
		(fp_line
			(start 0.12065 -0.305054)
			(end 0.12065 -0.2794)
			(stroke
				(width 0.1)
				(type default)
			)
			(layer "B.Fab")
		)
		(fp_line
			(start 0.67945 -0.305054)
			(end 0.12065 -0.305054)
			(stroke
				(width 0.1)
				(type default)
			)
			(layer "B.Fab")
		)
		(pad "1" smd circle
			(at 0.40005 0 90)
			(size 0 0)
			(layers "B.Cu" "B.Mask" "B.Paste")
			(net "P3V3_AUX")
		)
		(pad "2" smd circle
			(at -0.40005 0 90)
			(size 0 0)
			(layers "B.Cu" "B.Mask" "B.Paste")
			(net "SMB_BMC_MM4_SCL")
		)
	)
)
